(kicad_pcb
	(version 20260206)
	(generator "pcbnew")
	(generator_version "10.0")
	(general
		(thickness 1.6)
		(legacy_teardrops no)
	)
	(paper "A4")
	(title_block
		(title "panther-plus-userver — 13130-1b_20150205.brd")
		(comment 1 "Honey Badger (Wiwynn) / footprint 894 of 1509 (DIMM1), pads 100-106 of 210")
	)
	(layers
		(0 "F.Cu" signal "TOP")
		(4 "In1.Cu" signal "L2")
		(6 "In2.Cu" signal "L3")
		(8 "In3.Cu" signal "L4")
		(10 "In4.Cu" signal "L5")
		(12 "In5.Cu" signal "L6")
		(14 "In6.Cu" signal "L7")
		(16 "In7.Cu" signal "L8")
		(18 "In8.Cu" signal "L9")
		(20 "In9.Cu" signal "L10")
		(22 "In10.Cu" signal "L11")
		(2 "B.Cu" signal "BOTTOM")
		(9 "F.Adhes" user "F.Adhesive")
		(11 "B.Adhes" user "B.Adhesive")
		(13 "F.Paste" user "Package Geometry/Pastemask Top")
		(15 "B.Paste" user "Package Geometry/Pastemask Bottom")
		(5 "F.SilkS" user "Ref Des/Silkscreen Top")
		(7 "B.SilkS" user "Ref Des/Silkscreen Bottom")
		(1 "F.Mask" user "Board Geometry/Soldermask Top")
		(3 "B.Mask" user "Board Geometry/Soldermask Bottom")
		(17 "Dwgs.User" user "User.Drawings")
		(19 "Cmts.User" user "User.Comments")
		(21 "Eco1.User" user "User.Eco1")
		(23 "Eco2.User" user "User.Eco2")
		(25 "Edge.Cuts" user "Board Geometry/Outline")
		(27 "Margin" user)
		(31 "F.CrtYd" user "Package Geometry/Place Bound Top")
		(29 "B.CrtYd" user "Package Geometry/Place Bound Bottom")
		(35 "F.Fab" user "Ref Des/Assembly Top")
		(33 "B.Fab" user "Ref Des/Assembly Bottom")
	)
	(footprint ""
		(layer "B.Cu")
		(at 158.500064 -66.699892 180)
		(property "Reference" "DIMM1"
			(at 0 0 0)
			(layer "B.SilkS")
			(hide yes)
			(effects
				(font
					(size 1.27 1.27)
				)
				(justify mirror)
			)
		)
		(property "Value" "DDR3-204P-142-COLAY-1-GP-U"
			(at 41.312338 -16.676878 180)
			(unlocked yes)
			(layer "B.Fab")
			(hide yes)
			(effects
				(font
					(size 1.016 1.016)
					(thickness 0.1524)
				)
				(justify mirror)
			)
		)
		(property "Device Type" "AS0A626-J8R6-7H-COLAY-1"
			(at 41.312338 -18.200878 180)
			(unlocked yes)
			(layer "B.Fab")
			(hide yes)
			(effects
				(font
					(size 1.016 1.016)
					(thickness 0.1524)
				)
				(justify mirror)
			)
		)
		(duplicate_pad_numbers_are_jumpers no)
		(pad "98" smd custom
			(at -0.150114 4.100068)
			(size 0.1143 0.1143)
			(layers "B.Cu" "B.Mask" "B.Paste")
			(net "M_A_MA7")
			(options
				(clearance outline)
				(anchor circle)
			)
			(primitives
				(gr_poly
					(pts
						(xy 0 -0.9017) (xy -0.03175 -0.89916) (xy -0.0635 -0.889) (xy -0.09144 -0.87376) (xy -0.11684 -0.85344)
						(xy -0.13716 -0.82804) (xy -0.1524 -0.8001) (xy -0.16256 -0.76835) (xy -0.1651 -0.7366) (xy -0.1651 0.13462)
						(xy -0.17272 0.14224) (xy -0.19812 0.1778) (xy -0.2032 0.18796) (xy -0.20701 0.19685) (xy -0.21209 0.20701)
						(xy -0.2159 0.21717) (xy -0.21844 0.22733) (xy -0.22225 0.23876) (xy -0.22352 0.24892) (xy -0.22606 0.25908)
						(xy -0.22733 0.27051) (xy -0.22733 0.28067) (xy -0.2286 0.2921) (xy -0.22733 0.30353) (xy -0.22733 0.31369)
						(xy -0.22606 0.32512) (xy -0.22352 0.33528) (xy -0.22225 0.34544) (xy -0.21844 0.35687) (xy -0.2159 0.36703)
						(xy -0.21209 0.37719) (xy -0.20701 0.38735) (xy -0.2032 0.39624) (xy -0.19812 0.4064) (xy -0.17272 0.44196)
						(xy -0.1651 0.44958) (xy -0.1651 0.7366) (xy -0.16256 0.76835) (xy -0.1524 0.8001) (xy -0.13716 0.82804)
						(xy -0.11684 0.85344) (xy -0.09144 0.87376) (xy -0.0635 0.889) (xy -0.03175 0.89916) (xy 0 0.9017)
						(xy 0.03175 0.89916) (xy 0.0635 0.889) (xy 0.09144 0.87376) (xy 0.11684 0.85344) (xy 0.13716 0.82804)
						(xy 0.1524 0.8001) (xy 0.16256 0.76835) (xy 0.1651 0.7366) (xy 0.1651 0.44958) (xy 0.17272 0.44196)
						(xy 0.19812 0.4064) (xy 0.2032 0.39624) (xy 0.20701 0.38735) (xy 0.21209 0.37719) (xy 0.2159 0.36703)
						(xy 0.21844 0.35687) (xy 0.22225 0.34544) (xy 0.22352 0.33528) (xy 0.22606 0.32512) (xy 0.22733 0.31369)
						(xy 0.22733 0.30353) (xy 0.2286 0.2921) (xy 0.22733 0.28067) (xy 0.22733 0.27051) (xy 0.22606 0.25908)
						(xy 0.22352 0.24892) (xy 0.22225 0.23876) (xy 0.21844 0.22733) (xy 0.2159 0.21717) (xy 0.21209 0.20701)
						(xy 0.20701 0.19685) (xy 0.2032 0.18796) (xy 0.19812 0.1778) (xy 0.17272 0.14224) (xy 0.1651 0.13462)
						(xy 0.1651 -0.7366) (xy 0.16256 -0.76835) (xy 0.1524 -0.8001) (xy 0.13716 -0.82804) (xy 0.11684 -0.85344)
						(xy 0.09144 -0.87376) (xy 0.0635 -0.889) (xy 0.03175 -0.89916)
					)
					(width 0)
					(fill yes)
				)
			)
		)
		(pad "99" smd custom
			(at 0.150114 -4.100068)
			(size 0.1143 0.1143)
			(layers "B.Cu" "B.Mask" "B.Paste")
			(net "M_A_MA5")
			(options
				(clearance outline)
				(anchor circle)
			)
			(primitives
				(gr_poly
					(pts
						(xy 0 -0.9017) (xy -0.03175 -0.89916) (xy -0.0635 -0.889) (xy -0.09144 -0.87376) (xy -0.11684 -0.85344)
						(xy -0.13716 -0.82804) (xy -0.1524 -0.8001) (xy -0.16256 -0.76835) (xy -0.1651 -0.7366) (xy -0.1651 -0.19685)
						(xy -0.17272 -0.18923) (xy -0.17907 -0.18034) (xy -0.18669 -0.17145) (xy -0.19177 -0.16256) (xy -0.19812 -0.15367)
						(xy -0.20828 -0.13335) (xy -0.21971 -0.10287) (xy -0.22225 -0.09271) (xy -0.22479 -0.08128) (xy -0.22606 -0.07112)
						(xy -0.2286 -0.05969) (xy -0.2286 -0.01651) (xy -0.22606 -0.00508) (xy -0.22479 0.00508) (xy -0.22225 0.01651)
						(xy -0.21971 0.02667) (xy -0.20828 0.05715) (xy -0.19812 0.07747) (xy -0.19177 0.08636) (xy -0.18669 0.09525)
						(xy -0.17907 0.10414) (xy -0.17272 0.11303) (xy -0.1651 0.12065) (xy -0.1651 0.7366) (xy -0.16256 0.76835)
						(xy -0.1524 0.8001) (xy -0.13716 0.82804) (xy -0.11684 0.85344) (xy -0.09144 0.87376) (xy -0.0635 0.889)
						(xy -0.03175 0.89916) (xy 0 0.9017) (xy 0.03175 0.89916) (xy 0.0635 0.889) (xy 0.09144 0.87376)
						(xy 0.11684 0.85344) (xy 0.13716 0.82804) (xy 0.1524 0.8001) (xy 0.16256 0.76835) (xy 0.1651 0.7366)
						(xy 0.1651 0.11938) (xy 0.17272 0.11176) (xy 0.19812 0.0762) (xy 0.2032 0.06604) (xy 0.20701 0.05715)
						(xy 0.21209 0.04699) (xy 0.2159 0.03683) (xy 0.21844 0.02667) (xy 0.22225 0.01524) (xy 0.22352 0.00508)
						(xy 0.22606 -0.00508) (xy 0.22733 -0.01651) (xy 0.22733 -0.02667) (xy 0.2286 -0.0381) (xy 0.22733 -0.04953)
						(xy 0.22733 -0.05969) (xy 0.22606 -0.07112) (xy 0.22352 -0.08128) (xy 0.22225 -0.09144) (xy 0.21844 -0.10287)
						(xy 0.2159 -0.11303) (xy 0.21209 -0.12319) (xy 0.20701 -0.13335) (xy 0.2032 -0.14224) (xy 0.19812 -0.1524)
						(xy 0.17272 -0.18796) (xy 0.1651 -0.19558) (xy 0.1651 -0.7366) (xy 0.16256 -0.76835) (xy 0.1524 -0.8001)
						(xy 0.13716 -0.82804) (xy 0.11684 -0.85344) (xy 0.09144 -0.87376) (xy 0.0635 -0.889) (xy 0.03175 -0.89916)
					)
					(width 0)
					(fill yes)
				)
			)
		)
		(pad "100" smd custom
			(at 0.450088 4.100068)
			(size 0.1143 0.1143)
			(layers "B.Cu" "B.Mask" "B.Paste")
			(net "M_A_MA6")
			(options
				(clearance outline)
				(anchor circle)
			)
			(primitives
				(gr_poly
					(pts
						(xy 0 -0.9017) (xy -0.03175 -0.89916) (xy -0.0635 -0.889) (xy -0.09144 -0.87376) (xy -0.11684 -0.85344)
						(xy -0.13716 -0.82804) (xy -0.1524 -0.8001) (xy -0.16256 -0.76835) (xy -0.1651 -0.7366) (xy -0.1651 -0.11938)
						(xy -0.17272 -0.11176) (xy -0.19812 -0.0762) (xy -0.2032 -0.06604) (xy -0.20701 -0.05715) (xy -0.21209 -0.04699)
						(xy -0.2159 -0.03683) (xy -0.21844 -0.02667) (xy -0.22225 -0.01524) (xy -0.22352 -0.00508) (xy -0.22606 0.00508)
						(xy -0.22733 0.01651) (xy -0.22733 0.02667) (xy -0.2286 0.0381) (xy -0.22733 0.04953) (xy -0.22733 0.05969)
						(xy -0.22606 0.07112) (xy -0.22352 0.08128) (xy -0.22225 0.09144) (xy -0.21844 0.10287) (xy -0.2159 0.11303)
						(xy -0.21209 0.12319) (xy -0.20701 0.13335) (xy -0.2032 0.14224) (xy -0.19812 0.1524) (xy -0.17272 0.18796)
						(xy -0.1651 0.19558) (xy -0.1651 0.7366) (xy -0.16256 0.76835) (xy -0.1524 0.8001) (xy -0.13716 0.82804)
						(xy -0.11684 0.85344) (xy -0.09144 0.87376) (xy -0.0635 0.889) (xy -0.03175 0.89916) (xy 0 0.9017)
						(xy 0.03175 0.89916) (xy 0.0635 0.889) (xy 0.09144 0.87376) (xy 0.11684 0.85344) (xy 0.13716 0.82804)
						(xy 0.1524 0.8001) (xy 0.16256 0.76835) (xy 0.1651 0.7366) (xy 0.1651 0.19685) (xy 0.17272 0.18923)
						(xy 0.17907 0.18034) (xy 0.18669 0.17145) (xy 0.19177 0.16256) (xy 0.19812 0.15367) (xy 0.20828 0.13335)
						(xy 0.21971 0.10287) (xy 0.22225 0.09271) (xy 0.22479 0.08128) (xy 0.22606 0.07112) (xy 0.2286 0.05969)
						(xy 0.2286 0.01651) (xy 0.22606 0.00508) (xy 0.22479 -0.00508) (xy 0.22225 -0.01651) (xy 0.21971 -0.02667)
						(xy 0.20828 -0.05715) (xy 0.19812 -0.07747) (xy 0.19177 -0.08636) (xy 0.18669 -0.09525) (xy 0.17907 -0.10414)
						(xy 0.17272 -0.11303) (xy 0.1651 -0.12065) (xy 0.1651 -0.7366) (xy 0.16256 -0.76835) (xy 0.1524 -0.8001)
						(xy 0.13716 -0.82804) (xy 0.11684 -0.85344) (xy 0.09144 -0.87376) (xy 0.0635 -0.889) (xy 0.03175 -0.89916)
					)
					(width 0)
					(fill yes)
				)
			)
		)
		(pad "101" smd custom
			(at 0.750062 -4.100068)
			(size 0.1143 0.1143)
			(layers "B.Cu" "B.Mask" "B.Paste")
			(net "PV_VDDR")
			(options
				(clearance outline)
				(anchor circle)
			)
			(primitives
				(gr_poly
					(pts
						(xy 0 -0.9017) (xy -0.03175 -0.89916) (xy -0.0635 -0.889) (xy -0.09144 -0.87376) (xy -0.11684 -0.85344)
						(xy -0.13716 -0.82804) (xy -0.1524 -0.8001) (xy -0.16256 -0.76835) (xy -0.1651 -0.7366) (xy -0.1651 -0.44958)
						(xy -0.17272 -0.44196) (xy -0.19812 -0.4064) (xy -0.2032 -0.39624) (xy -0.20701 -0.38735) (xy -0.21209 -0.37719)
						(xy -0.2159 -0.36703) (xy -0.21844 -0.35687) (xy -0.22225 -0.34544) (xy -0.22352 -0.33528) (xy -0.22606 -0.32512)
						(xy -0.22733 -0.31369) (xy -0.22733 -0.30353) (xy -0.2286 -0.2921) (xy -0.22733 -0.28067) (xy -0.22733 -0.27051)
						(xy -0.22606 -0.25908) (xy -0.22352 -0.24892) (xy -0.22225 -0.23876) (xy -0.21844 -0.22733) (xy -0.2159 -0.21717)
						(xy -0.21209 -0.20701) (xy -0.20701 -0.19685) (xy -0.2032 -0.18796) (xy -0.19812 -0.1778) (xy -0.17272 -0.14224)
						(xy -0.1651 -0.13462) (xy -0.1651 0.7366) (xy -0.16256 0.76835) (xy -0.1524 0.8001) (xy -0.13716 0.82804)
						(xy -0.11684 0.85344) (xy -0.09144 0.87376) (xy -0.0635 0.889) (xy -0.03175 0.89916) (xy 0 0.9017)
						(xy 0.03175 0.89916) (xy 0.0635 0.889) (xy 0.09144 0.87376) (xy 0.11684 0.85344) (xy 0.13716 0.82804)
						(xy 0.1524 0.8001) (xy 0.16256 0.76835) (xy 0.1651 0.7366) (xy 0.1651 -0.13462) (xy 0.17272 -0.14224)
						(xy 0.19812 -0.1778) (xy 0.2032 -0.18796) (xy 0.20701 -0.19685) (xy 0.21209 -0.20701) (xy 0.2159 -0.21717)
						(xy 0.21844 -0.22733) (xy 0.22225 -0.23876) (xy 0.22352 -0.24892) (xy 0.22606 -0.25908) (xy 0.22733 -0.27051)
						(xy 0.22733 -0.28067) (xy 0.2286 -0.2921) (xy 0.22733 -0.30353) (xy 0.22733 -0.31369) (xy 0.22606 -0.32512)
						(xy 0.22352 -0.33528) (xy 0.22225 -0.34544) (xy 0.21844 -0.35687) (xy 0.2159 -0.36703) (xy 0.21209 -0.37719)
						(xy 0.20701 -0.38735) (xy 0.2032 -0.39624) (xy 0.19812 -0.4064) (xy 0.17272 -0.44196) (xy 0.1651 -0.44958)
						(xy 0.1651 -0.7366) (xy 0.16256 -0.76835) (xy 0.1524 -0.8001) (xy 0.13716 -0.82804) (xy 0.11684 -0.85344)
						(xy 0.09144 -0.87376) (xy 0.0635 -0.889) (xy 0.03175 -0.89916)
					)
					(width 0)
					(fill yes)
				)
			)
		)
		(pad "102" smd custom
			(at 1.050036 4.100068)
			(size 0.1143 0.1143)
			(layers "B.Cu" "B.Mask" "B.Paste")
			(net "PV_VDDR")
			(options
				(clearance outline)
				(anchor circle)
			)
			(primitives
				(gr_poly
					(pts
						(xy 0 -0.9017) (xy -0.03175 -0.89916) (xy -0.0635 -0.889) (xy -0.09144 -0.87376) (xy -0.11684 -0.85344)
						(xy -0.13716 -0.82804) (xy -0.1524 -0.8001) (xy -0.16256 -0.76835) (xy -0.1651 -0.7366) (xy -0.1651 0.13462)
						(xy -0.17272 0.14224) (xy -0.19812 0.1778) (xy -0.2032 0.18796) (xy -0.20701 0.19685) (xy -0.21209 0.20701)
						(xy -0.2159 0.21717) (xy -0.21844 0.22733) (xy -0.22225 0.23876) (xy -0.22352 0.24892) (xy -0.22606 0.25908)
						(xy -0.22733 0.27051) (xy -0.22733 0.28067) (xy -0.2286 0.2921) (xy -0.22733 0.30353) (xy -0.22733 0.31369)
						(xy -0.22606 0.32512) (xy -0.22352 0.33528) (xy -0.22225 0.34544) (xy -0.21844 0.35687) (xy -0.2159 0.36703)
						(xy -0.21209 0.37719) (xy -0.20701 0.38735) (xy -0.2032 0.39624) (xy -0.19812 0.4064) (xy -0.17272 0.44196)
						(xy -0.1651 0.44958) (xy -0.1651 0.7366) (xy -0.16256 0.76835) (xy -0.1524 0.8001) (xy -0.13716 0.82804)
						(xy -0.11684 0.85344) (xy -0.09144 0.87376) (xy -0.0635 0.889) (xy -0.03175 0.89916) (xy 0 0.9017)
						(xy 0.03175 0.89916) (xy 0.0635 0.889) (xy 0.09144 0.87376) (xy 0.11684 0.85344) (xy 0.13716 0.82804)
						(xy 0.1524 0.8001) (xy 0.16256 0.76835) (xy 0.1651 0.7366) (xy 0.1651 0.44958) (xy 0.17272 0.44196)
						(xy 0.19812 0.4064) (xy 0.2032 0.39624) (xy 0.20701 0.38735) (xy 0.21209 0.37719) (xy 0.2159 0.36703)
						(xy 0.21844 0.35687) (xy 0.22225 0.34544) (xy 0.22352 0.33528) (xy 0.22606 0.32512) (xy 0.22733 0.31369)
						(xy 0.22733 0.30353) (xy 0.2286 0.2921) (xy 0.22733 0.28067) (xy 0.22733 0.27051) (xy 0.22606 0.25908)
						(xy 0.22352 0.24892) (xy 0.22225 0.23876) (xy 0.21844 0.22733) (xy 0.2159 0.21717) (xy 0.21209 0.20701)
						(xy 0.20701 0.19685) (xy 0.2032 0.18796) (xy 0.19812 0.1778) (xy 0.17272 0.14224) (xy 0.1651 0.13462)
						(xy 0.1651 -0.7366) (xy 0.16256 -0.76835) (xy 0.1524 -0.8001) (xy 0.13716 -0.82804) (xy 0.11684 -0.85344)
						(xy 0.09144 -0.87376) (xy 0.0635 -0.889) (xy 0.03175 -0.89916)
					)
					(width 0)
					(fill yes)
				)
			)
		)
		(pad "103" smd custom
			(at 1.35001 -4.100068)
			(size 0.1143 0.1143)
			(layers "B.Cu" "B.Mask" "B.Paste")
			(net "M_A_MA3")
			(options
				(clearance outline)
				(anchor circle)
			)
			(primitives
				(gr_poly
					(pts
						(xy 0 -0.9017) (xy -0.03175 -0.89916) (xy -0.0635 -0.889) (xy -0.09144 -0.87376) (xy -0.11684 -0.85344)
						(xy -0.13716 -0.82804) (xy -0.1524 -0.8001) (xy -0.16256 -0.76835) (xy -0.1651 -0.7366) (xy -0.1651 -0.19685)
						(xy -0.17272 -0.18923) (xy -0.17907 -0.18034) (xy -0.18669 -0.17145) (xy -0.19177 -0.16256) (xy -0.19812 -0.15367)
						(xy -0.20828 -0.13335) (xy -0.21971 -0.10287) (xy -0.22225 -0.09271) (xy -0.22479 -0.08128) (xy -0.22606 -0.07112)
						(xy -0.2286 -0.05969) (xy -0.2286 -0.01651) (xy -0.22606 -0.00508) (xy -0.22479 0.00508) (xy -0.22225 0.01651)
						(xy -0.21971 0.02667) (xy -0.20828 0.05715) (xy -0.19812 0.07747) (xy -0.19177 0.08636) (xy -0.18669 0.09525)
						(xy -0.17907 0.10414) (xy -0.17272 0.11303) (xy -0.1651 0.12065) (xy -0.1651 0.7366) (xy -0.16256 0.76835)
						(xy -0.1524 0.8001) (xy -0.13716 0.82804) (xy -0.11684 0.85344) (xy -0.09144 0.87376) (xy -0.0635 0.889)
						(xy -0.03175 0.89916) (xy 0 0.9017) (xy 0.03175 0.89916) (xy 0.0635 0.889) (xy 0.09144 0.87376)
						(xy 0.11684 0.85344) (xy 0.13716 0.82804) (xy 0.1524 0.8001) (xy 0.16256 0.76835) (xy 0.1651 0.7366)
						(xy 0.1651 0.11938) (xy 0.17272 0.11176) (xy 0.19812 0.0762) (xy 0.2032 0.06604) (xy 0.20701 0.05715)
						(xy 0.21209 0.04699) (xy 0.2159 0.03683) (xy 0.21844 0.02667) (xy 0.22225 0.01524) (xy 0.22352 0.00508)
						(xy 0.22606 -0.00508) (xy 0.22733 -0.01651) (xy 0.22733 -0.02667) (xy 0.2286 -0.0381) (xy 0.22733 -0.04953)
						(xy 0.22733 -0.05969) (xy 0.22606 -0.07112) (xy 0.22352 -0.08128) (xy 0.22225 -0.09144) (xy 0.21844 -0.10287)
						(xy 0.2159 -0.11303) (xy 0.21209 -0.12319) (xy 0.20701 -0.13335) (xy 0.2032 -0.14224) (xy 0.19812 -0.1524)
						(xy 0.17272 -0.18796) (xy 0.1651 -0.19558) (xy 0.1651 -0.7366) (xy 0.16256 -0.76835) (xy 0.1524 -0.8001)
						(xy 0.13716 -0.82804) (xy 0.11684 -0.85344) (xy 0.09144 -0.87376) (xy 0.0635 -0.889) (xy 0.03175 -0.89916)
					)
					(width 0)
					(fill yes)
				)
			)
		)
		(pad "104" smd custom
			(at 1.649984 4.100068)
			(size 0.1143 0.1143)
			(layers "B.Cu" "B.Mask" "B.Paste")
			(net "M_A_MA4")
			(options
				(clearance outline)
				(anchor circle)
			)
			(primitives
				(gr_poly
					(pts
						(xy 0 -0.9017) (xy -0.03175 -0.89916) (xy -0.0635 -0.889) (xy -0.09144 -0.87376) (xy -0.11684 -0.85344)
						(xy -0.13716 -0.82804) (xy -0.1524 -0.8001) (xy -0.16256 -0.76835) (xy -0.1651 -0.7366) (xy -0.1651 -0.11938)
						(xy -0.17272 -0.11176) (xy -0.19812 -0.0762) (xy -0.2032 -0.06604) (xy -0.20701 -0.05715) (xy -0.21209 -0.04699)
						(xy -0.2159 -0.03683) (xy -0.21844 -0.02667) (xy -0.22225 -0.01524) (xy -0.22352 -0.00508) (xy -0.22606 0.00508)
						(xy -0.22733 0.01651) (xy -0.22733 0.02667) (xy -0.2286 0.0381) (xy -0.22733 0.04953) (xy -0.22733 0.05969)
						(xy -0.22606 0.07112) (xy -0.22352 0.08128) (xy -0.22225 0.09144) (xy -0.21844 0.10287) (xy -0.2159 0.11303)
						(xy -0.21209 0.12319) (xy -0.20701 0.13335) (xy -0.2032 0.14224) (xy -0.19812 0.1524) (xy -0.17272 0.18796)
						(xy -0.1651 0.19558) (xy -0.1651 0.7366) (xy -0.16256 0.76835) (xy -0.1524 0.8001) (xy -0.13716 0.82804)
						(xy -0.11684 0.85344) (xy -0.09144 0.87376) (xy -0.0635 0.889) (xy -0.03175 0.89916) (xy 0 0.9017)
						(xy 0.03175 0.89916) (xy 0.0635 0.889) (xy 0.09144 0.87376) (xy 0.11684 0.85344) (xy 0.13716 0.82804)
						(xy 0.1524 0.8001) (xy 0.16256 0.76835) (xy 0.1651 0.7366) (xy 0.1651 0.19685) (xy 0.17272 0.18923)
						(xy 0.17907 0.18034) (xy 0.18669 0.17145) (xy 0.19177 0.16256) (xy 0.19812 0.15367) (xy 0.20828 0.13335)
						(xy 0.21971 0.10287) (xy 0.22225 0.09271) (xy 0.22479 0.08128) (xy 0.22606 0.07112) (xy 0.2286 0.05969)
						(xy 0.2286 0.01651) (xy 0.22606 0.00508) (xy 0.22479 -0.00508) (xy 0.22225 -0.01651) (xy 0.21971 -0.02667)
						(xy 0.20828 -0.05715) (xy 0.19812 -0.07747) (xy 0.19177 -0.08636) (xy 0.18669 -0.09525) (xy 0.17907 -0.10414)
						(xy 0.17272 -0.11303) (xy 0.1651 -0.12065) (xy 0.1651 -0.7366) (xy 0.16256 -0.76835) (xy 0.1524 -0.8001)
						(xy 0.13716 -0.82804) (xy 0.11684 -0.85344) (xy 0.09144 -0.87376) (xy 0.0635 -0.889) (xy 0.03175 -0.89916)
					)
					(width 0)
					(fill yes)
				)
			)
		)
	)
)
